# SCM (Grand Teton) — schematic netlist excerpt (pin names and nets, part order shuffled) for the footprints in the layout excerpt that follows; sources: Cadence DE-HDL packaged netlist, KiCad conversion of 12092022_DA0F0TMDCD0_F0T_Management_Board_D_brd_V3_OCP.brd

D23  Q_DIODE  SDMK0340L-7-F EMPTY  pkg SMLF  page 35 : \1\ = PWRGD_P5V_AUX ; \2\ = PWRGD_P5V_AUX_R1
C250  Q_CAP  0.1UF 25V 10% X7R  pkg 0402  page 41 : A = PVCCA_AUX_PLD ; B = GND

(kicad_pcb
	(version 20260206)
	(generator "pcbnew")
	(generator_version "10.0")
	(general
		(thickness 1.6)
		(legacy_teardrops no)
	)
	(paper "A4")
	(title_block
		(title "12092022_DA0F0TMDCD0_F0T_Management_Board_D_brd_V3_OCP.brd")
		(comment 1 "Grand Teton / footprints 1173-1174 of 1440")
	)
	(layers
		(0 "F.Cu" signal "TOP")
		(4 "In1.Cu" signal "GND")
		(6 "In2.Cu" signal "IN1")
		(8 "In3.Cu" signal "GND1")
		(10 "In4.Cu" signal "IN2")
		(12 "In5.Cu" signal "VCC")
		(14 "In6.Cu" signal "VCC1")
		(16 "In7.Cu" signal "IN3")
		(18 "In8.Cu" signal "GND2")
		(20 "In9.Cu" signal "IN4")
		(22 "In10.Cu" signal "GND3")
		(2 "B.Cu" signal "BOTTOM")
		(9 "F.Adhes" user "F.Adhesive")
		(11 "B.Adhes" user "B.Adhesive")
		(13 "F.Paste" user "Package Geometry/Pastemask Top")
		(15 "B.Paste" user "Package Geometry/Pastemask Bottom")
		(5 "F.SilkS" user "Ref Des/Silkscreen Top")
		(7 "B.SilkS" user "Ref Des/Silkscreen Bottom")
		(1 "F.Mask" user "Board Geometry/Soldermask Top")
		(3 "B.Mask" user "Board Geometry/Soldermask Bottom")
		(17 "Dwgs.User" user "User.Drawings")
		(19 "Cmts.User" user "User.Comments")
		(21 "Eco1.User" user "User.Eco1")
		(23 "Eco2.User" user "User.Eco2")
		(25 "Edge.Cuts" user "Board Geometry/Outline")
		(27 "Margin" user)
		(31 "F.CrtYd" user "Package Geometry/Place Bound Top")
		(29 "B.CrtYd" user "Package Geometry/Place Bound Bottom")
		(35 "F.Fab" user "Ref Des/Assembly Top")
		(33 "B.Fab" user "Ref Des/Assembly Bottom")
	)
	(footprint ""
		(layer "B.Cu")
		(at 12.319 -101.854 90)
		(property "Reference" "D23"
			(at -0.0762 1.37033 270)
			(unlocked yes)
			(layer "B.SilkS")
			(effects
				(font
					(size 0.7874 0.5842)
					(thickness 0.1524)
				)
				(justify left mirror)
			)
		)
		(property "Value" ""
			(at 0 0 90)
			(layer "B.Fab")
			(effects
				(font
					(size 1.27 1.27)
				)
				(justify mirror)
			)
		)
		(duplicate_pad_numbers_are_jumpers no)
		(fp_line
			(start 2.050796 -0.700024)
			(end -2.050796 -0.700024)
			(stroke
				(width 0.1524)
				(type default)
			)
			(layer "B.SilkS")
		)
		(fp_line
			(start -2.050796 -0.700024)
			(end -2.050796 0.700024)
			(stroke
				(width 0.1524)
				(type default)
			)
			(layer "B.SilkS")
		)
		(fp_line
			(start -2.064004 -0.6985)
			(end -2.229104 -0.6985)
			(stroke
				(width 0.1524)
				(type default)
			)
			(layer "B.SilkS")
		)
		(fp_line
			(start -2.152904 -0.6985)
			(end -2.343404 -0.6985)
			(stroke
				(width 0.1524)
				(type default)
			)
			(layer "B.SilkS")
		)
		(fp_line
			(start -2.229104 -0.6985)
			(end -2.229104 0.6985)
			(stroke
				(width 0.1524)
				(type default)
			)
			(layer "B.SilkS")
		)
		(fp_line
			(start -2.343404 -0.6985)
			(end -2.343404 0.6985)
			(stroke
				(width 0.1524)
				(type default)
			)
			(layer "B.SilkS")
		)
		(fp_line
			(start -2.064004 -0.6731)
			(end -2.064004 -0.6985)
			(stroke
				(width 0.1524)
				(type default)
			)
			(layer "B.SilkS")
		)
		(fp_line
			(start 0.30607 -0.500126)
			(end 0.30607 0.500126)
			(stroke
				(width 0.1524)
				(type default)
			)
			(layer "B.SilkS")
		)
		(fp_line
			(start -0.293878 -0.500126)
			(end -0.293878 0.500126)
			(stroke
				(width 0.1524)
				(type default)
			)
			(layer "B.SilkS")
		)
		(fp_line
			(start -0.193802 0)
			(end 0.30607 -0.500126)
			(stroke
				(width 0.1524)
				(type default)
			)
			(layer "B.SilkS")
		)
		(fp_line
			(start 0.30607 0.500126)
			(end -0.193802 0)
			(stroke
				(width 0.1524)
				(type default)
			)
			(layer "B.SilkS")
		)
		(fp_line
			(start -2.051304 0.635)
			(end -2.152904 0.635)
			(stroke
				(width 0.1524)
				(type default)
			)
			(layer "B.SilkS")
		)
		(fp_line
			(start -2.152904 0.635)
			(end -2.152904 -0.6985)
			(stroke
				(width 0.1524)
				(type default)
			)
			(layer "B.SilkS")
		)
		(fp_line
			(start -2.051304 0.6985)
			(end -2.051304 0.635)
			(stroke
				(width 0.1524)
				(type default)
			)
			(layer "B.SilkS")
		)
		(fp_line
			(start -2.229104 0.6985)
			(end -2.051304 0.6985)
			(stroke
				(width 0.1524)
				(type default)
			)
			(layer "B.SilkS")
		)
		(fp_line
			(start -2.343404 0.6985)
			(end -2.216404 0.6985)
			(stroke
				(width 0.1524)
				(type default)
			)
			(layer "B.SilkS")
		)
		(fp_line
			(start 2.050796 0.700024)
			(end 2.050796 -0.700024)
			(stroke
				(width 0.1524)
				(type default)
			)
			(layer "B.SilkS")
		)
		(fp_line
			(start -2.050796 0.700024)
			(end 2.050796 0.700024)
			(stroke
				(width 0.1524)
				(type default)
			)
			(layer "B.SilkS")
		)
		(fp_line
			(start 0.899922 -0.700024)
			(end -0.899922 -0.700024)
			(stroke
				(width 0.1)
				(type default)
			)
			(layer "B.Fab")
		)
		(fp_line
			(start -0.899922 -0.700024)
			(end -0.899922 0.700024)
			(stroke
				(width 0.1)
				(type default)
			)
			(layer "B.Fab")
		)
		(fp_line
			(start 0.899922 0.700024)
			(end 0.899922 -0.700024)
			(stroke
				(width 0.1)
				(type default)
			)
			(layer "B.Fab")
		)
		(fp_line
			(start -0.899922 0.700024)
			(end 0.899922 0.700024)
			(stroke
				(width 0.1)
				(type default)
			)
			(layer "B.Fab")
		)
		(fp_text user "+"
			(at 3.01625 1.016 0)
			(unlocked yes)
			(layer "B.SilkS")
			(effects
				(font
					(size 1.905 1.4224)
					(thickness 0.1524)
				)
				(justify left mirror)
			)
		)
		(fp_text user "-"
			(at -2.2352 1.36525 270)
			(unlocked yes)
			(layer "B.SilkS")
			(effects
				(font
					(size 1.905 1.4224)
					(thickness 0.1524)
				)
				(justify left mirror)
			)
		)
		(fp_text user "-"
			(at -3.880104 0.23495 270)
			(unlocked yes)
			(layer "B.Fab")
			(effects
				(font
					(size 1.905 1.4224)
					(thickness 0.1524)
				)
				(justify left mirror)
			)
		)
		(fp_text user "+"
			(at 3.123946 0.762 0)
			(unlocked yes)
			(layer "B.Fab")
			(effects
				(font
					(size 1.905 1.4224)
					(thickness 0.1524)
				)
				(justify left mirror)
			)
		)
		(pad "1" smd rect
			(at 1.199896 0)
			(size 0.6604 1.3716)
			(layers "B.Cu" "B.Mask" "B.Paste")
			(net "PWRGD_P5V_AUX")
		)
		(pad "2" smd rect
			(at -1.199896 0 180)
			(size 0.6604 1.3716)
			(layers "B.Cu" "B.Mask" "B.Paste")
			(net "PWRGD_P5V_AUX_R1")
		)
	)
	(footprint ""
		(layer "B.Cu")
		(at 19.472656 -96.012 -90)
		(property "Reference" "C250"
			(at 0 0 90)
			(layer "B.SilkS")
			(hide yes)
			(effects
				(font
					(size 1.27 1.27)
				)
				(justify mirror)
			)
		)
		(property "Value" ""
			(at 0 0 90)
			(layer "B.Fab")
			(effects
				(font
					(size 1.27 1.27)
				)
				(justify mirror)
			)
		)
		(duplicate_pad_numbers_are_jumpers no)
		(fp_line
			(start -0.69215 0.2921)
			(end 0.69215 0.2921)
			(stroke
				(width 0.1524)
				(type default)
			)
			(layer "B.SilkS")
		)
		(fp_line
			(start 0.69215 0.2921)
			(end 0.69215 -0.2921)
			(stroke
				(width 0.1524)
				(type default)
			)
			(layer "B.SilkS")
		)
		(fp_line
			(start -0.69215 -0.2921)
			(end -0.69215 0.2921)
			(stroke
				(width 0.1524)
				(type default)
			)
			(layer "B.SilkS")
		)
		(fp_line
			(start 0.69215 -0.2921)
			(end -0.69215 -0.2921)
			(stroke
				(width 0.1524)
				(type default)
			)
			(layer "B.SilkS")
		)
		(fp_line
			(start -0.51435 0.2794)
			(end 0.51435 0.2794)
			(stroke
				(width 0.1)
				(type default)
			)
			(layer "B.Fab")
		)
		(fp_line
			(start 0.51435 0.2794)
			(end 0.51435 -0.2794)
			(stroke
				(width 0.1)
				(type default)
			)
			(layer "B.Fab")
		)
		(fp_line
			(start -0.51435 -0.2794)
			(end -0.51435 0.2794)
			(stroke
				(width 0.1)
				(type default)
			)
			(layer "B.Fab")
		)
		(fp_line
			(start 0.51435 -0.2794)
			(end -0.51435 -0.2794)
			(stroke
				(width 0.1)
				(type default)
			)
			(layer "B.Fab")
		)
		(pad "1" smd circle
			(at 0.40005 0 90)
			(size 0 0)
			(layers "B.Cu" "B.Mask" "B.Paste")
			(net "PVCCA_AUX_PLD")
		)
		(pad "2" smd circle
			(at -0.40005 0 90)
			(size 0 0)
			(layers "B.Cu" "B.Mask" "B.Paste")
			(net "GND")
		)
		(zone
			(layer "B.Cu")
			(hatch none 0.5)
			(connect_pads
				(clearance 0)
			)
			(min_thickness 0.25)
			(keepout
				(tracks not_allowed)
				(vias allowed)
				(pads allowed)
				(copperpour not_allowed)
				(footprints allowed)
			)
			(placement
				(enabled no)
				(sheetname "")
			)
			(fill
				(thermal_gap 0.5)
				(thermal_bridge_width 0.5)
				(island_removal_mode 0)
			)
			(polygon
				(pts
					(xy 19.385026 -95.8215) (xy 19.32686 -95.91294) (xy 19.32686 -96.11233) (xy 19.385026 -96.2025)
					(xy 19.560286 -96.2025) (xy 19.618706 -96.11233) (xy 19.618706 -95.91294) (xy 19.56054 -95.8215)
				)
			)
		)
	)
)
